(kicad_pcb
	(version 20260206)
	(generator "pcbnew")
	(generator_version "10.0")
	(general
		(thickness 1.6)
		(legacy_teardrops no)
	)
	(paper "A4")
	(title_block
		(title "04192023_DAF0TMB3IC0_F0TG_MB_C_brd_V02_OCP.brd")
		(comment 1 "Grand Teton / footprints 2810-2816 of 8354")
	)
	(layers
		(0 "F.Cu" signal "TOP")
		(4 "In1.Cu" signal "GND")
		(6 "In2.Cu" signal "IN1")
		(8 "In3.Cu" signal "GND1")
		(10 "In4.Cu" signal "IN2")
		(12 "In5.Cu" signal "GND2")
		(14 "In6.Cu" signal "IN3")
		(16 "In7.Cu" signal "GND3")
		(18 "In8.Cu" signal "VCC")
		(20 "In9.Cu" signal "VCC1")
		(22 "In10.Cu" signal "GND4")
		(24 "In11.Cu" signal "IN4")
		(26 "In12.Cu" signal "GND5")
		(28 "In13.Cu" signal "IN5")
		(30 "In14.Cu" signal "GND6")
		(32 "In15.Cu" signal "IN6")
		(34 "In16.Cu" signal "GND7")
		(2 "B.Cu" signal "BOTTOM")
		(9 "F.Adhes" user "F.Adhesive")
		(11 "B.Adhes" user "B.Adhesive")
		(13 "F.Paste" user "Package Geometry/Pastemask Top")
		(15 "B.Paste" user "Package Geometry/Pastemask Bottom")
		(5 "F.SilkS" user "Ref Des/Silkscreen Top")
		(7 "B.SilkS" user "Ref Des/Silkscreen Bottom")
		(1 "F.Mask" user "Board Geometry/Soldermask Top")
		(3 "B.Mask" user "Board Geometry/Soldermask Bottom")
		(17 "Dwgs.User" user "User.Drawings")
		(19 "Cmts.User" user "User.Comments")
		(21 "Eco1.User" user "User.Eco1")
		(23 "Eco2.User" user "User.Eco2")
		(25 "Edge.Cuts" user "Board Geometry/Outline")
		(27 "Margin" user)
		(31 "F.CrtYd" user "Package Geometry/Place Bound Top")
		(29 "B.CrtYd" user "Package Geometry/Place Bound Bottom")
		(35 "F.Fab" user "Ref Des/Assembly Top")
		(33 "B.Fab" user "Ref Des/Assembly Bottom")
	)
	(footprint ""
		(layer "F.Cu")
		(at 181.9402 -96.103948 -90)
		(property "Reference" "R179"
			(at 0 0 270)
			(layer "F.SilkS")
			(hide yes)
			(effects
				(font
					(size 1.27 1.27)
				)
			)
		)
		(property "Value" ""
			(at 0 0 270)
			(layer "F.Fab")
			(effects
				(font
					(size 1.27 1.27)
				)
			)
		)
		(duplicate_pad_numbers_are_jumpers no)
		(fp_line
			(start -0.7874 0.4064)
			(end -0.7874 -0.4064)
			(stroke
				(width 0.1524)
				(type default)
			)
			(layer "F.SilkS")
		)
		(fp_line
			(start 0.7874 0.4064)
			(end -0.7874 0.4064)
			(stroke
				(width 0.1524)
				(type default)
			)
			(layer "F.SilkS")
		)
		(fp_line
			(start -0.7874 -0.4064)
			(end 0.7874 -0.4064)
			(stroke
				(width 0.1524)
				(type default)
			)
			(layer "F.SilkS")
		)
		(fp_line
			(start 0.7874 -0.4064)
			(end 0.7874 0.4064)
			(stroke
				(width 0.1524)
				(type default)
			)
			(layer "F.SilkS")
		)
		(fp_line
			(start -0.67945 0.3048)
			(end -0.67945 -0.305054)
			(stroke
				(width 0.1)
				(type default)
			)
			(layer "F.Fab")
		)
		(fp_line
			(start -0.12065 0.3048)
			(end -0.67945 0.3048)
			(stroke
				(width 0.1)
				(type default)
			)
			(layer "F.Fab")
		)
		(fp_line
			(start 0.120396 0.3048)
			(end 0.120396 0.2794)
			(stroke
				(width 0.1)
				(type default)
			)
			(layer "F.Fab")
		)
		(fp_line
			(start 0.67945 0.3048)
			(end 0.120396 0.3048)
			(stroke
				(width 0.1)
				(type default)
			)
			(layer "F.Fab")
		)
		(fp_line
			(start -0.12065 0.2794)
			(end -0.12065 0.3048)
			(stroke
				(width 0.1)
				(type default)
			)
			(layer "F.Fab")
		)
		(fp_line
			(start 0.120396 0.2794)
			(end -0.12065 0.2794)
			(stroke
				(width 0.1)
				(type default)
			)
			(layer "F.Fab")
		)
		(fp_line
			(start -0.12065 -0.2794)
			(end 0.12065 -0.2794)
			(stroke
				(width 0.1)
				(type default)
			)
			(layer "F.Fab")
		)
		(fp_line
			(start 0.12065 -0.2794)
			(end 0.12065 -0.3048)
			(stroke
				(width 0.1)
				(type default)
			)
			(layer "F.Fab")
		)
		(fp_line
			(start 0.12065 -0.3048)
			(end 0.67945 -0.3048)
			(stroke
				(width 0.1)
				(type default)
			)
			(layer "F.Fab")
		)
		(fp_line
			(start 0.67945 -0.3048)
			(end 0.67945 0.3048)
			(stroke
				(width 0.1)
				(type default)
			)
			(layer "F.Fab")
		)
		(fp_line
			(start -0.67945 -0.305054)
			(end -0.12065 -0.305054)
			(stroke
				(width 0.1)
				(type default)
			)
			(layer "F.Fab")
		)
		(fp_line
			(start -0.12065 -0.305054)
			(end -0.12065 -0.2794)
			(stroke
				(width 0.1)
				(type default)
			)
			(layer "F.Fab")
		)
		(pad "1" smd circle
			(at -0.40005 0 270)
			(size 0 0)
			(layers "F.Cu" "F.Mask" "F.Paste")
			(net "FM_CPU0_PROCHOT_R_N")
		)
		(pad "2" smd circle
			(at 0.40005 0 270)
			(size 0 0)
			(layers "F.Cu" "F.Mask" "F.Paste")
			(net "CPU0_PROCHOT_N")
		)
	)
	(footprint ""
		(layer "F.Cu")
		(at 320.921888 -22.571456 90)
		(property "Reference" "R130"
			(at 0 0 90)
			(layer "F.SilkS")
			(hide yes)
			(effects
				(font
					(size 1.27 1.27)
				)
			)
		)
		(property "Value" ""
			(at 0 0 90)
			(layer "F.Fab")
			(effects
				(font
					(size 1.27 1.27)
				)
			)
		)
		(duplicate_pad_numbers_are_jumpers no)
		(fp_line
			(start 0.7874 -0.4064)
			(end 0.7874 0.4064)
			(stroke
				(width 0.1524)
				(type default)
			)
			(layer "F.SilkS")
		)
		(fp_line
			(start -0.7874 -0.4064)
			(end 0.7874 -0.4064)
			(stroke
				(width 0.1524)
				(type default)
			)
			(layer "F.SilkS")
		)
		(fp_line
			(start 0.7874 0.4064)
			(end -0.7874 0.4064)
			(stroke
				(width 0.1524)
				(type default)
			)
			(layer "F.SilkS")
		)
		(fp_line
			(start -0.7874 0.4064)
			(end -0.7874 -0.4064)
			(stroke
				(width 0.1524)
				(type default)
			)
			(layer "F.SilkS")
		)
		(fp_line
			(start -0.12065 -0.305054)
			(end -0.12065 -0.2794)
			(stroke
				(width 0.1)
				(type default)
			)
			(layer "F.Fab")
		)
		(fp_line
			(start -0.67945 -0.305054)
			(end -0.12065 -0.305054)
			(stroke
				(width 0.1)
				(type default)
			)
			(layer "F.Fab")
		)
		(fp_line
			(start 0.67945 -0.3048)
			(end 0.67945 0.3048)
			(stroke
				(width 0.1)
				(type default)
			)
			(layer "F.Fab")
		)
		(fp_line
			(start 0.12065 -0.3048)
			(end 0.67945 -0.3048)
			(stroke
				(width 0.1)
				(type default)
			)
			(layer "F.Fab")
		)
		(fp_line
			(start 0.12065 -0.2794)
			(end 0.12065 -0.3048)
			(stroke
				(width 0.1)
				(type default)
			)
			(layer "F.Fab")
		)
		(fp_line
			(start -0.12065 -0.2794)
			(end 0.12065 -0.2794)
			(stroke
				(width 0.1)
				(type default)
			)
			(layer "F.Fab")
		)
		(fp_line
			(start 0.120396 0.2794)
			(end -0.12065 0.2794)
			(stroke
				(width 0.1)
				(type default)
			)
			(layer "F.Fab")
		)
		(fp_line
			(start -0.12065 0.2794)
			(end -0.12065 0.3048)
			(stroke
				(width 0.1)
				(type default)
			)
			(layer "F.Fab")
		)
		(fp_line
			(start 0.67945 0.3048)
			(end 0.120396 0.3048)
			(stroke
				(width 0.1)
				(type default)
			)
			(layer "F.Fab")
		)
		(fp_line
			(start 0.120396 0.3048)
			(end 0.120396 0.2794)
			(stroke
				(width 0.1)
				(type default)
			)
			(layer "F.Fab")
		)
		(fp_line
			(start -0.12065 0.3048)
			(end -0.67945 0.3048)
			(stroke
				(width 0.1)
				(type default)
			)
			(layer "F.Fab")
		)
		(fp_line
			(start -0.67945 0.3048)
			(end -0.67945 -0.305054)
			(stroke
				(width 0.1)
				(type default)
			)
			(layer "F.Fab")
		)
		(pad "1" smd circle
			(at -0.40005 0 90)
			(size 0 0)
			(layers "F.Cu" "F.Mask" "F.Paste")
			(net "UART_VCC_J8")
		)
		(pad "2" smd circle
			(at 0.40005 0 90)
			(size 0 0)
			(layers "F.Cu" "F.Mask" "F.Paste")
			(net "P5V_AUX")
		)
	)
	(footprint ""
		(layer "F.Cu")
		(at 330.523342 -393.86256)
		(property "Reference" "R1027"
			(at 0 0 0)
			(layer "F.SilkS")
			(hide yes)
			(effects
				(font
					(size 1.27 1.27)
				)
			)
		)
		(property "Value" ""
			(at 0 0 0)
			(layer "F.Fab")
			(effects
				(font
					(size 1.27 1.27)
				)
			)
		)
		(duplicate_pad_numbers_are_jumpers no)
		(fp_line
			(start -0.32512 -0.175006)
			(end 0.32512 -0.175006)
			(stroke
				(width 0.1)
				(type default)
			)
			(layer "F.Fab")
		)
		(fp_line
			(start -0.32512 0.175006)
			(end -0.32512 -0.175006)
			(stroke
				(width 0.1)
				(type default)
			)
			(layer "F.Fab")
		)
		(fp_line
			(start 0.32512 -0.175006)
			(end 0.32512 0.175006)
			(stroke
				(width 0.1)
				(type default)
			)
			(layer "F.Fab")
		)
		(fp_line
			(start 0.32512 0.175006)
			(end -0.32512 0.175006)
			(stroke
				(width 0.1)
				(type default)
			)
			(layer "F.Fab")
		)
		(pad "1" smd rect
			(at -0.2667 0)
			(size 0.3048 0.381)
			(layers "F.Cu" "F.Mask" "F.Paste")
			(net "P1V8_CPU0_RT_1D")
		)
		(pad "2" smd rect
			(at 0.2667 0 180)
			(size 0.3048 0.381)
			(layers "F.Cu" "F.Mask" "F.Paste")
			(net "GPIO2_RT_CPU0_P1")
		)
	)
	(footprint ""
		(layer "F.Cu")
		(at 152.018492 -117.944646 180)
		(property "Reference" "C1561"
			(at 0 0 180)
			(layer "F.SilkS")
			(hide yes)
			(effects
				(font
					(size 1.27 1.27)
				)
			)
		)
		(property "Value" ""
			(at 0 0 180)
			(layer "F.Fab")
			(effects
				(font
					(size 1.27 1.27)
				)
			)
		)
		(duplicate_pad_numbers_are_jumpers no)
		(fp_line
			(start 0.7874 0.4064)
			(end -0.7874 0.4064)
			(stroke
				(width 0.1524)
				(type default)
			)
			(layer "F.SilkS")
		)
		(fp_line
			(start 0.7874 -0.4064)
			(end 0.7874 0.4064)
			(stroke
				(width 0.1524)
				(type default)
			)
			(layer "F.SilkS")
		)
		(fp_line
			(start -0.7874 0.4064)
			(end -0.7874 -0.4064)
			(stroke
				(width 0.1524)
				(type default)
			)
			(layer "F.SilkS")
		)
		(fp_line
			(start -0.7874 -0.4064)
			(end 0.7874 -0.4064)
			(stroke
				(width 0.1524)
				(type default)
			)
			(layer "F.SilkS")
		)
		(fp_line
			(start 0.67945 0.3048)
			(end 0.120396 0.3048)
			(stroke
				(width 0.1)
				(type default)
			)
			(layer "F.Fab")
		)
		(fp_line
			(start 0.67945 -0.3048)
			(end 0.67945 0.3048)
			(stroke
				(width 0.1)
				(type default)
			)
			(layer "F.Fab")
		)
		(fp_line
			(start 0.12065 -0.2794)
			(end 0.12065 -0.3048)
			(stroke
				(width 0.1)
				(type default)
			)
			(layer "F.Fab")
		)
		(fp_line
			(start 0.12065 -0.3048)
			(end 0.67945 -0.3048)
			(stroke
				(width 0.1)
				(type default)
			)
			(layer "F.Fab")
		)
		(fp_line
			(start 0.120396 0.3048)
			(end 0.120396 0.2794)
			(stroke
				(width 0.1)
				(type default)
			)
			(layer "F.Fab")
		)
		(fp_line
			(start 0.120396 0.2794)
			(end -0.12065 0.2794)
			(stroke
				(width 0.1)
				(type default)
			)
			(layer "F.Fab")
		)
		(fp_line
			(start -0.12065 0.3048)
			(end -0.67945 0.3048)
			(stroke
				(width 0.1)
				(type default)
			)
			(layer "F.Fab")
		)
		(fp_line
			(start -0.12065 0.2794)
			(end -0.12065 0.3048)
			(stroke
				(width 0.1)
				(type default)
			)
			(layer "F.Fab")
		)
		(fp_line
			(start -0.12065 -0.2794)
			(end 0.12065 -0.2794)
			(stroke
				(width 0.1)
				(type default)
			)
			(layer "F.Fab")
		)
		(fp_line
			(start -0.12065 -0.305054)
			(end -0.12065 -0.2794)
			(stroke
				(width 0.1)
				(type default)
			)
			(layer "F.Fab")
		)
		(fp_line
			(start -0.67945 0.3048)
			(end -0.67945 -0.305054)
			(stroke
				(width 0.1)
				(type default)
			)
			(layer "F.Fab")
		)
		(fp_line
			(start -0.67945 -0.305054)
			(end -0.12065 -0.305054)
			(stroke
				(width 0.1)
				(type default)
			)
			(layer "F.Fab")
		)
		(pad "1" smd circle
			(at -0.40005 0 180)
			(size 0 0)
			(layers "F.Cu" "F.Mask" "F.Paste")
			(net "U206_VS")
		)
		(pad "2" smd circle
			(at 0.40005 0 180)
			(size 0 0)
			(layers "F.Cu" "F.Mask" "F.Paste")
			(net "GND")
		)
	)
	(footprint ""
		(layer "F.Cu")
		(at 77.215746 -394.166852 -90)
		(property "Reference" "R752"
			(at 0 0 270)
			(layer "F.SilkS")
			(hide yes)
			(effects
				(font
					(size 1.27 1.27)
				)
			)
		)
		(property "Value" ""
			(at 0 0 270)
			(layer "F.Fab")
			(effects
				(font
					(size 1.27 1.27)
				)
			)
		)
		(duplicate_pad_numbers_are_jumpers no)
		(fp_line
			(start -0.32512 0.175006)
			(end -0.32512 -0.175006)
			(stroke
				(width 0.1)
				(type default)
			)
			(layer "F.Fab")
		)
		(fp_line
			(start 0.32512 0.175006)
			(end -0.32512 0.175006)
			(stroke
				(width 0.1)
				(type default)
			)
			(layer "F.Fab")
		)
		(fp_line
			(start -0.32512 -0.175006)
			(end 0.32512 -0.175006)
			(stroke
				(width 0.1)
				(type default)
			)
			(layer "F.Fab")
		)
		(fp_line
			(start 0.32512 -0.175006)
			(end 0.32512 0.175006)
			(stroke
				(width 0.1)
				(type default)
			)
			(layer "F.Fab")
		)
		(pad "1" smd rect
			(at -0.2667 0 270)
			(size 0.3048 0.381)
			(layers "F.Cu" "F.Mask" "F.Paste")
			(net "RST_RT_CPU1_P1_RESET_R_N")
		)
		(pad "2" smd rect
			(at 0.2667 0 90)
			(size 0.3048 0.381)
			(layers "F.Cu" "F.Mask" "F.Paste")
			(net "GND")
		)
	)
	(footprint ""
		(layer "F.Cu")
		(at 250.55957 -68.946522)
		(property "Reference" "R4063"
			(at 0 0 0)
			(layer "F.SilkS")
			(hide yes)
			(effects
				(font
					(size 1.27 1.27)
				)
			)
		)
		(property "Value" ""
			(at 0 0 0)
			(layer "F.Fab")
			(effects
				(font
					(size 1.27 1.27)
				)
			)
		)
		(duplicate_pad_numbers_are_jumpers no)
		(fp_line
			(start -0.7874 -0.4064)
			(end 0.7874 -0.4064)
			(stroke
				(width 0.1524)
				(type default)
			)
			(layer "F.SilkS")
		)
		(fp_line
			(start -0.7874 0.4064)
			(end -0.7874 -0.4064)
			(stroke
				(width 0.1524)
				(type default)
			)
			(layer "F.SilkS")
		)
		(fp_line
			(start 0.7874 -0.4064)
			(end 0.7874 0.4064)
			(stroke
				(width 0.1524)
				(type default)
			)
			(layer "F.SilkS")
		)
		(fp_line
			(start 0.7874 0.4064)
			(end -0.7874 0.4064)
			(stroke
				(width 0.1524)
				(type default)
			)
			(layer "F.SilkS")
		)
		(fp_line
			(start -0.67945 -0.305054)
			(end -0.12065 -0.305054)
			(stroke
				(width 0.1)
				(type default)
			)
			(layer "F.Fab")
		)
		(fp_line
			(start -0.67945 0.3048)
			(end -0.67945 -0.305054)
			(stroke
				(width 0.1)
				(type default)
			)
			(layer "F.Fab")
		)
		(fp_line
			(start -0.12065 -0.305054)
			(end -0.12065 -0.2794)
			(stroke
				(width 0.1)
				(type default)
			)
			(layer "F.Fab")
		)
		(fp_line
			(start -0.12065 -0.2794)
			(end 0.12065 -0.2794)
			(stroke
				(width 0.1)
				(type default)
			)
			(layer "F.Fab")
		)
		(fp_line
			(start -0.12065 0.2794)
			(end -0.12065 0.3048)
			(stroke
				(width 0.1)
				(type default)
			)
			(layer "F.Fab")
		)
		(fp_line
			(start -0.12065 0.3048)
			(end -0.67945 0.3048)
			(stroke
				(width 0.1)
				(type default)
			)
			(layer "F.Fab")
		)
		(fp_line
			(start 0.120396 0.2794)
			(end -0.12065 0.2794)
			(stroke
				(width 0.1)
				(type default)
			)
			(layer "F.Fab")
		)
		(fp_line
			(start 0.120396 0.3048)
			(end 0.120396 0.2794)
			(stroke
				(width 0.1)
				(type default)
			)
			(layer "F.Fab")
		)
		(fp_line
			(start 0.12065 -0.3048)
			(end 0.67945 -0.3048)
			(stroke
				(width 0.1)
				(type default)
			)
			(layer "F.Fab")
		)
		(fp_line
			(start 0.12065 -0.2794)
			(end 0.12065 -0.3048)
			(stroke
				(width 0.1)
				(type default)
			)
			(layer "F.Fab")
		)
		(fp_line
			(start 0.67945 -0.3048)
			(end 0.67945 0.3048)
			(stroke
				(width 0.1)
				(type default)
			)
			(layer "F.Fab")
		)
		(fp_line
			(start 0.67945 0.3048)
			(end 0.120396 0.3048)
			(stroke
				(width 0.1)
				(type default)
			)
			(layer "F.Fab")
		)
		(pad "1" smd circle
			(at -0.40005 0)
			(size 0 0)
			(layers "F.Cu" "F.Mask" "F.Paste")
			(net "E1S_0_P3V3_EN")
		)
		(pad "2" smd circle
			(at 0.40005 0)
			(size 0 0)
			(layers "F.Cu" "F.Mask" "F.Paste")
			(net "P3V3_E1S_EN_0_R")
		)
	)
	(footprint ""
		(layer "F.Cu")
		(at 95.39097 -60.86221 180)
		(property "Reference" "PR3795"
			(at 0 0 180)
			(layer "F.SilkS")
			(hide yes)
			(effects
				(font
					(size 1.27 1.27)
				)
			)
		)
		(property "Value" ""
			(at 0 0 180)
			(layer "F.Fab")
			(effects
				(font
					(size 1.27 1.27)
				)
			)
		)
		(duplicate_pad_numbers_are_jumpers no)
		(fp_line
			(start 0.7874 0.4064)
			(end -0.7874 0.4064)
			(stroke
				(width 0.1524)
				(type default)
			)
			(layer "F.SilkS")
		)
		(fp_line
			(start 0.7874 -0.4064)
			(end 0.7874 0.4064)
			(stroke
				(width 0.1524)
				(type default)
			)
			(layer "F.SilkS")
		)
		(fp_line
			(start -0.7874 0.4064)
			(end -0.7874 -0.4064)
			(stroke
				(width 0.1524)
				(type default)
			)
			(layer "F.SilkS")
		)
		(fp_line
			(start -0.7874 -0.4064)
			(end 0.7874 -0.4064)
			(stroke
				(width 0.1524)
				(type default)
			)
			(layer "F.SilkS")
		)
		(fp_line
			(start 0.67945 0.3048)
			(end 0.120396 0.3048)
			(stroke
				(width 0.1)
				(type default)
			)
			(layer "F.Fab")
		)
		(fp_line
			(start 0.67945 -0.3048)
			(end 0.67945 0.3048)
			(stroke
				(width 0.1)
				(type default)
			)
			(layer "F.Fab")
		)
		(fp_line
			(start 0.12065 -0.2794)
			(end 0.12065 -0.3048)
			(stroke
				(width 0.1)
				(type default)
			)
			(layer "F.Fab")
		)
		(fp_line
			(start 0.12065 -0.3048)
			(end 0.67945 -0.3048)
			(stroke
				(width 0.1)
				(type default)
			)
			(layer "F.Fab")
		)
		(fp_line
			(start 0.120396 0.3048)
			(end 0.120396 0.2794)
			(stroke
				(width 0.1)
				(type default)
			)
			(layer "F.Fab")
		)
		(fp_line
			(start 0.120396 0.2794)
			(end -0.12065 0.2794)
			(stroke
				(width 0.1)
				(type default)
			)
			(layer "F.Fab")
		)
		(fp_line
			(start -0.12065 0.3048)
			(end -0.67945 0.3048)
			(stroke
				(width 0.1)
				(type default)
			)
			(layer "F.Fab")
		)
		(fp_line
			(start -0.12065 0.2794)
			(end -0.12065 0.3048)
			(stroke
				(width 0.1)
				(type default)
			)
			(layer "F.Fab")
		)
		(fp_line
			(start -0.12065 -0.2794)
			(end 0.12065 -0.2794)
			(stroke
				(width 0.1)
				(type default)
			)
			(layer "F.Fab")
		)
		(fp_line
			(start -0.12065 -0.305054)
			(end -0.12065 -0.2794)
			(stroke
				(width 0.1)
				(type default)
			)
			(layer "F.Fab")
		)
		(fp_line
			(start -0.67945 0.3048)
			(end -0.67945 -0.305054)
			(stroke
				(width 0.1)
				(type default)
			)
			(layer "F.Fab")
		)
		(fp_line
			(start -0.67945 -0.305054)
			(end -0.12065 -0.305054)
			(stroke
				(width 0.1)
				(type default)
			)
			(layer "F.Fab")
		)
		(pad "1" smd circle
			(at -0.40005 0 180)
			(size 0 0)
			(layers "F.Cu" "F.Mask" "F.Paste")
			(net "P3V3_AUX")
		)
		(pad "2" smd circle
			(at 0.40005 0 180)
			(size 0 0)
			(layers "F.Cu" "F.Mask" "F.Paste")
			(net "P3V3_OCP_UV_2")
		)
	)
)
